(kicad_pcb
	(version 20260206)
	(generator "pcbnew")
	(generator_version "10.0")
	(general
		(thickness 1.6)
		(legacy_teardrops no)
	)
	(paper "A4")
	(title_block
		(title "Wiwynn_Tioga_Pass_MB.brd")
		(comment 1 "Tioga Pass / footprints 468-475 of 4770")
	)
	(layers
		(0 "F.Cu" signal "TOP")
		(4 "In1.Cu" signal "L2GND")
		(6 "In2.Cu" signal "L3")
		(8 "In3.Cu" signal "L4GND")
		(10 "In4.Cu" signal "L5")
		(12 "In5.Cu" signal "L6GND")
		(14 "In6.Cu" signal "L7VCC")
		(16 "In7.Cu" signal "L8VCC")
		(18 "In8.Cu" signal "L9GND")
		(20 "In9.Cu" signal "L10")
		(22 "In10.Cu" signal "L11GND")
		(24 "In11.Cu" signal "L12")
		(26 "In12.Cu" signal "L13GND")
		(2 "B.Cu" signal "BOTTOM")
		(9 "F.Adhes" user "F.Adhesive")
		(11 "B.Adhes" user "B.Adhesive")
		(13 "F.Paste" user "Package Geometry/Pastemask Top")
		(15 "B.Paste" user "Package Geometry/Pastemask Bottom")
		(5 "F.SilkS" user "Ref Des/Silkscreen Top")
		(7 "B.SilkS" user "Ref Des/Silkscreen Bottom")
		(1 "F.Mask" user "Board Geometry/Soldermask Top")
		(3 "B.Mask" user "Board Geometry/Soldermask Bottom")
		(17 "Dwgs.User" user "User.Drawings")
		(19 "Cmts.User" user "User.Comments")
		(21 "Eco1.User" user "User.Eco1")
		(23 "Eco2.User" user "User.Eco2")
		(25 "Edge.Cuts" user "Board Geometry/Outline")
		(27 "Margin" user)
		(31 "F.CrtYd" user "Package Geometry/Place Bound Top")
		(29 "B.CrtYd" user "Package Geometry/Place Bound Bottom")
		(35 "F.Fab" user "Ref Des/Assembly Top")
		(33 "B.Fab" user "Ref Des/Assembly Bottom")
	)
	(footprint ""
		(layer "F.Cu")
		(at 436.8165 -15.367 90)
		(property "Reference" "R1U41"
			(at 0 0 90)
			(layer "F.SilkS")
			(hide yes)
			(effects
				(font
					(size 1.27 1.27)
				)
			)
		)
		(property "Value" ""
			(at 0 0 90)
			(layer "F.Fab")
			(effects
				(font
					(size 1.27 1.27)
				)
			)
		)
		(duplicate_pad_numbers_are_jumpers no)
		(fp_poly
			(pts
				(xy -0.2794 -0.1016) (xy 0.2794 -0.1016) (xy 0.2794 0.9906) (xy -0.2794 0.9906)
			)
			(stroke
				(width 0)
				(type default)
			)
			(fill no)
			(layer "F.CrtYd")
		)
		(fp_line
			(start 0.2794 -0.1016)
			(end -0.2794 -0.1016)
			(stroke
				(width 0.1)
				(type default)
			)
			(layer "F.Fab")
		)
		(fp_line
			(start -0.2794 -0.1016)
			(end -0.2794 0.9906)
			(stroke
				(width 0.1)
				(type default)
			)
			(layer "F.Fab")
		)
		(fp_line
			(start 0.2794 0.9906)
			(end 0.2794 -0.1016)
			(stroke
				(width 0.1)
				(type default)
			)
			(layer "F.Fab")
		)
		(fp_line
			(start -0.2794 0.9906)
			(end 0.2794 0.9906)
			(stroke
				(width 0.1)
				(type default)
			)
			(layer "F.Fab")
		)
		(pad "1" smd rect
			(at 0 0 90)
			(size 0.508 0.508)
			(layers "F.Cu" "F.Mask" "F.Paste")
			(net "PVCCIO_CPU1")
		)
		(pad "2" smd rect
			(at 0 0.889 90)
			(size 0.508 0.508)
			(layers "F.Cu" "F.Mask" "F.Paste")
			(net "H_CPU1_MEMGHJ_MEMHOT_G_N")
		)
		(zone
			(layer "F.Cu")
			(hatch none 0.5)
			(connect_pads
				(clearance 0)
			)
			(min_thickness 0.25)
			(keepout
				(tracks allowed)
				(vias not_allowed)
				(pads allowed)
				(copperpour not_allowed)
				(footprints allowed)
			)
			(placement
				(enabled no)
				(sheetname "")
			)
			(fill
				(thermal_gap 0.5)
				(thermal_bridge_width 0.5)
				(island_removal_mode 0)
			)
			(polygon
				(pts
					(xy 437.0705 -15.113) (xy 437.0705 -15.621) (xy 437.4515 -15.621) (xy 437.4515 -15.113)
				)
			)
		)
		(zone
			(layer "F.Cu")
			(hatch none 0.5)
			(connect_pads
				(clearance 0)
			)
			(min_thickness 0.25)
			(keepout
				(tracks not_allowed)
				(vias allowed)
				(pads allowed)
				(copperpour not_allowed)
				(footprints allowed)
			)
			(placement
				(enabled no)
				(sheetname "")
			)
			(fill
				(thermal_gap 0.5)
				(thermal_bridge_width 0.5)
				(island_removal_mode 0)
			)
			(polygon
				(pts
					(xy 437.4515 -15.113) (xy 437.4515 -15.621) (xy 437.0705 -15.621) (xy 437.0705 -15.113)
				)
			)
		)
	)
	(footprint ""
		(layer "F.Cu")
		(at 44.1071 -51.3334 90)
		(property "Reference" "RT8P1"
			(at 1.27127 0.4699 180)
			(unlocked yes)
			(layer "F.SilkS")
			(effects
				(font
					(size 0.7874 0.5842)
					(thickness 0.1524)
				)
			)
		)
		(property "Value" ""
			(at 0 0 90)
			(layer "F.Fab")
			(effects
				(font
					(size 1.27 1.27)
				)
			)
		)
		(duplicate_pad_numbers_are_jumpers no)
		(fp_poly
			(pts
				(xy -0.4953 -0.2032) (xy 0.4953 -0.2032) (xy 0.4953 1.6002) (xy -0.4953 1.6002)
			)
			(stroke
				(width 0)
				(type default)
			)
			(fill no)
			(layer "F.CrtYd")
		)
		(fp_line
			(start 0.4953 -0.2032)
			(end 0.4953 1.6002)
			(stroke
				(width 0.1)
				(type default)
			)
			(layer "F.Fab")
		)
		(fp_line
			(start -0.4953 -0.2032)
			(end 0.4953 -0.2032)
			(stroke
				(width 0.1)
				(type default)
			)
			(layer "F.Fab")
		)
		(fp_line
			(start 0.4953 1.6002)
			(end -0.4953 1.6002)
			(stroke
				(width 0.1)
				(type default)
			)
			(layer "F.Fab")
		)
		(fp_line
			(start -0.4953 1.6002)
			(end -0.4953 -0.2032)
			(stroke
				(width 0.1)
				(type default)
			)
			(layer "F.Fab")
		)
		(pad "1" smd rect
			(at 0 0 90)
			(size 0.762 0.889)
			(layers "F.Cu" "F.Mask" "F.Paste")
			(net "PVCCIN_CPU1")
		)
		(pad "2" smd rect
			(at 0 1.397 90)
			(size 0.762 0.889)
			(layers "F.Cu" "F.Mask" "F.Paste")
			(net "VSENSE_VCCINR2PMAX_CPU1")
		)
		(zone
			(layer "F.Cu")
			(hatch none 0.5)
			(connect_pads
				(clearance 0)
			)
			(min_thickness 0.25)
			(keepout
				(tracks allowed)
				(vias not_allowed)
				(pads allowed)
				(copperpour not_allowed)
				(footprints allowed)
			)
			(placement
				(enabled no)
				(sheetname "")
			)
			(fill
				(thermal_gap 0.5)
				(thermal_bridge_width 0.5)
				(island_removal_mode 0)
			)
			(polygon
				(pts
					(xy 45.0596 -51.7144) (xy 44.5516 -51.7144) (xy 44.5516 -50.9524) (xy 45.0596 -50.9524)
				)
			)
		)
		(zone
			(layer "F.Cu")
			(hatch none 0.5)
			(connect_pads
				(clearance 0)
			)
			(min_thickness 0.25)
			(keepout
				(tracks not_allowed)
				(vias allowed)
				(pads allowed)
				(copperpour not_allowed)
				(footprints allowed)
			)
			(placement
				(enabled no)
				(sheetname "")
			)
			(fill
				(thermal_gap 0.5)
				(thermal_bridge_width 0.5)
				(island_removal_mode 0)
			)
			(polygon
				(pts
					(xy 45.0596 -50.9524) (xy 45.0596 -51.7144) (xy 44.5516 -51.7144) (xy 44.5516 -50.9524)
				)
			)
		)
	)
	(footprint ""
		(layer "F.Cu")
		(at 369.8494 -129.286 90)
		(property "Reference" "R7B6"
			(at 0 0 90)
			(layer "F.SilkS")
			(hide yes)
			(effects
				(font
					(size 1.27 1.27)
				)
			)
		)
		(property "Value" ""
			(at 0 0 90)
			(layer "F.Fab")
			(effects
				(font
					(size 1.27 1.27)
				)
			)
		)
		(duplicate_pad_numbers_are_jumpers no)
		(fp_poly
			(pts
				(xy -0.2794 -0.1016) (xy 0.2794 -0.1016) (xy 0.2794 0.9906) (xy -0.2794 0.9906)
			)
			(stroke
				(width 0)
				(type default)
			)
			(fill no)
			(layer "F.CrtYd")
		)
		(fp_line
			(start 0.2794 -0.1016)
			(end -0.2794 -0.1016)
			(stroke
				(width 0.1)
				(type default)
			)
			(layer "F.Fab")
		)
		(fp_line
			(start -0.2794 -0.1016)
			(end -0.2794 0.9906)
			(stroke
				(width 0.1)
				(type default)
			)
			(layer "F.Fab")
		)
		(fp_line
			(start 0.2794 0.9906)
			(end 0.2794 -0.1016)
			(stroke
				(width 0.1)
				(type default)
			)
			(layer "F.Fab")
		)
		(fp_line
			(start -0.2794 0.9906)
			(end 0.2794 0.9906)
			(stroke
				(width 0.1)
				(type default)
			)
			(layer "F.Fab")
		)
		(pad "1" smd rect
			(at 0 0 90)
			(size 0.508 0.508)
			(layers "F.Cu" "F.Mask" "F.Paste")
			(net "P3V3_STBY")
		)
		(pad "2" smd rect
			(at 0 0.889 90)
			(size 0.508 0.508)
			(layers "F.Cu" "F.Mask" "F.Paste")
			(net "FM_PCH_PRSNT_N")
		)
		(zone
			(layer "F.Cu")
			(hatch none 0.5)
			(connect_pads
				(clearance 0)
			)
			(min_thickness 0.25)
			(keepout
				(tracks allowed)
				(vias not_allowed)
				(pads allowed)
				(copperpour not_allowed)
				(footprints allowed)
			)
			(placement
				(enabled no)
				(sheetname "")
			)
			(fill
				(thermal_gap 0.5)
				(thermal_bridge_width 0.5)
				(island_removal_mode 0)
			)
			(polygon
				(pts
					(xy 370.1034 -129.032) (xy 370.1034 -129.54) (xy 370.4844 -129.54) (xy 370.4844 -129.032)
				)
			)
		)
		(zone
			(layer "F.Cu")
			(hatch none 0.5)
			(connect_pads
				(clearance 0)
			)
			(min_thickness 0.25)
			(keepout
				(tracks not_allowed)
				(vias allowed)
				(pads allowed)
				(copperpour not_allowed)
				(footprints allowed)
			)
			(placement
				(enabled no)
				(sheetname "")
			)
			(fill
				(thermal_gap 0.5)
				(thermal_bridge_width 0.5)
				(island_removal_mode 0)
			)
			(polygon
				(pts
					(xy 370.4844 -129.032) (xy 370.4844 -129.54) (xy 370.1034 -129.54) (xy 370.1034 -129.032)
				)
			)
		)
	)
	(footprint ""
		(layer "F.Cu")
		(at 454.29932 -128.25222 -90)
		(property "Reference" "F9B1"
			(at 0 0 270)
			(layer "F.SilkS")
			(hide yes)
			(effects
				(font
					(size 1.27 1.27)
				)
			)
		)
		(property "Value" ""
			(at 0 0 270)
			(layer "F.Fab")
			(effects
				(font
					(size 1.27 1.27)
				)
			)
		)
		(duplicate_pad_numbers_are_jumpers no)
		(fp_poly
			(pts
				(xy 1.7018 4.7117) (xy -1.7018 4.7117) (xy -1.7018 -0.0127) (xy 1.7018 -0.0127)
			)
			(stroke
				(width 0)
				(type default)
			)
			(fill no)
			(layer "F.CrtYd")
		)
		(fp_line
			(start -1.7018 4.7117)
			(end -1.7018 -0.0127)
			(stroke
				(width 0.1)
				(type default)
			)
			(layer "F.Fab")
		)
		(fp_line
			(start 1.7018 4.7117)
			(end -1.7018 4.7117)
			(stroke
				(width 0.1)
				(type default)
			)
			(layer "F.Fab")
		)
		(fp_line
			(start -1.7018 -0.0127)
			(end 1.7018 -0.0127)
			(stroke
				(width 0.1)
				(type default)
			)
			(layer "F.Fab")
		)
		(fp_line
			(start 1.7018 -0.0127)
			(end 1.7018 4.7117)
			(stroke
				(width 0.1)
				(type default)
			)
			(layer "F.Fab")
		)
		(pad "1" smd rect
			(at 0 0 270)
			(size 3.302 1.397)
			(layers "F.Cu" "F.Mask" "F.Paste")
			(net "P12V")
		)
		(pad "2" smd rect
			(at 0 4.699 270)
			(size 3.302 1.397)
			(layers "F.Cu" "F.Mask" "F.Paste")
			(net "P12V_HDD_SATA")
		)
		(zone
			(layers "F.Cu" "B.Cu" "In1.Cu" "In2.Cu" "In3.Cu" "In4.Cu" "In5.Cu" "In6.Cu"
				"In7.Cu" "In8.Cu" "In9.Cu" "In10.Cu" "In11.Cu" "In12.Cu"
			)
			(hatch none 0.5)
			(connect_pads
				(clearance 0)
			)
			(min_thickness 0.25)
			(keepout
				(tracks allowed)
				(vias not_allowed)
				(pads allowed)
				(copperpour not_allowed)
				(footprints allowed)
			)
			(placement
				(enabled no)
				(sheetname "")
			)
			(fill
				(thermal_gap 0.5)
				(thermal_bridge_width 0.5)
				(island_removal_mode 0)
			)
			(polygon
				(pts
					(xy 450.29882 -129.90322) (xy 450.29882 -126.60122) (xy 453.60082 -126.60122) (xy 453.60082 -129.90322)
				)
			)
		)
	)
	(footprint ""
		(layer "F.Cu")
		(at 24.7015 -84.455)
		(property "Reference" "U1D1"
			(at -0.3683 -2.25933 0)
			(unlocked yes)
			(layer "F.SilkS")
			(effects
				(font
					(size 0.7874 0.5842)
					(thickness 0.1524)
				)
				(justify left)
			)
		)
		(property "Value" ""
			(at 0 0 0)
			(layer "F.Fab")
			(effects
				(font
					(size 1.27 1.27)
				)
			)
		)
		(duplicate_pad_numbers_are_jumpers no)
		(fp_circle
			(center -0.160782 -0.675386)
			(end -0.033782 -0.675386)
			(stroke
				(width 0.254)
				(type default)
			)
			(fill no)
			(layer "F.SilkS")
		)
		(fp_poly
			(pts
				(xy 0.21463 -0.450088) (xy 1.56337 -0.450088) (xy 1.56337 1.75006) (xy 0.21463 1.75006)
			)
			(stroke
				(width 0)
				(type default)
			)
			(fill no)
			(layer "F.CrtYd")
		)
		(fp_line
			(start 0.21463 -0.450088)
			(end 1.56337 -0.450088)
			(stroke
				(width 0.1)
				(type default)
			)
			(layer "F.Fab")
		)
		(fp_line
			(start 0.21463 1.75006)
			(end 0.21463 -0.450088)
			(stroke
				(width 0.1)
				(type default)
			)
			(layer "F.Fab")
		)
		(fp_line
			(start 1.56337 -0.450088)
			(end 1.56337 1.75006)
			(stroke
				(width 0.1)
				(type default)
			)
			(layer "F.Fab")
		)
		(fp_line
			(start 1.56337 1.75006)
			(end 0.21463 1.75006)
			(stroke
				(width 0.1)
				(type default)
			)
			(layer "F.Fab")
		)
		(fp_circle
			(center -0.4699 -0.8382)
			(end -0.3429 -0.8382)
			(stroke
				(width 0.254)
				(type default)
			)
			(fill no)
			(layer "F.Fab")
		)
		(pad "1" smd rect
			(at 0 0)
			(size 1.016 0.381)
			(layers "F.Cu" "F.Mask" "F.Paste")
			(net "FM_OC_DETECT_EN")
		)
		(pad "2" smd rect
			(at 0 0.649986)
			(size 1.016 0.381)
			(layers "F.Cu" "F.Mask" "F.Paste")
			(net "IRQ_OC_DETECT_N")
		)
		(pad "3" smd rect
			(at 0 1.299972)
			(size 1.016 0.381)
			(layers "F.Cu" "F.Mask" "F.Paste")
			(net "GND")
		)
		(pad "4" smd rect
			(at 1.778 1.299972)
			(size 1.016 0.381)
			(layers "F.Cu" "F.Mask" "F.Paste")
			(net "FM_OC_DETECT_N")
		)
		(pad "5" smd rect
			(at 1.778 0)
			(size 1.016 0.381)
			(layers "F.Cu" "F.Mask" "F.Paste")
			(net "P3V3_STBY")
		)
	)
	(footprint ""
		(layer "F.Cu")
		(at 95.69704 -81.573116)
		(property "Reference" "C2D11"
			(at 0 0 0)
			(layer "F.SilkS")
			(hide yes)
			(effects
				(font
					(size 1.27 1.27)
				)
			)
		)
		(property "Value" ""
			(at 0 0 0)
			(layer "F.Fab")
			(effects
				(font
					(size 1.27 1.27)
				)
			)
		)
		(duplicate_pad_numbers_are_jumpers no)
		(fp_poly
			(pts
				(xy -0.4953 -0.2032) (xy 0.4953 -0.2032) (xy 0.4953 1.6002) (xy -0.4953 1.6002)
			)
			(stroke
				(width 0)
				(type default)
			)
			(fill no)
			(layer "F.CrtYd")
		)
		(fp_line
			(start -0.4953 -0.2032)
			(end 0.4953 -0.2032)
			(stroke
				(width 0.1)
				(type default)
			)
			(layer "F.Fab")
		)
		(fp_line
			(start -0.4953 1.6002)
			(end -0.4953 -0.2032)
			(stroke
				(width 0.1)
				(type default)
			)
			(layer "F.Fab")
		)
		(fp_line
			(start 0.4953 -0.2032)
			(end 0.4953 1.6002)
			(stroke
				(width 0.1)
				(type default)
			)
			(layer "F.Fab")
		)
		(fp_line
			(start 0.4953 1.6002)
			(end -0.4953 1.6002)
			(stroke
				(width 0.1)
				(type default)
			)
			(layer "F.Fab")
		)
		(pad "1" smd rect
			(at 0 0)
			(size 0.762 0.889)
			(layers "F.Cu" "F.Mask" "F.Paste")
			(net "PVSA_CPU1")
		)
		(pad "2" smd rect
			(at 0 1.397)
			(size 0.762 0.889)
			(layers "F.Cu" "F.Mask" "F.Paste")
			(net "GND")
		)
		(zone
			(layer "F.Cu")
			(hatch none 0.5)
			(connect_pads
				(clearance 0)
			)
			(min_thickness 0.25)
			(keepout
				(tracks not_allowed)
				(vias allowed)
				(pads allowed)
				(copperpour not_allowed)
				(footprints allowed)
			)
			(placement
				(enabled no)
				(sheetname "")
			)
			(fill
				(thermal_gap 0.5)
				(thermal_bridge_width 0.5)
				(island_removal_mode 0)
			)
			(polygon
				(pts
					(xy 95.31604 -81.128616) (xy 96.07804 -81.128616) (xy 96.07804 -80.620616) (xy 95.31604 -80.620616)
				)
			)
		)
	)
	(footprint ""
		(layer "F.Cu")
		(at 411.6578 -102.4636 180)
		(property "Reference" "R7W12"
			(at -0.8382 -0.67818 180)
			(unlocked yes)
			(layer "F.SilkS")
			(effects
				(font
					(size 0.4064 0.254)
					(thickness 0.1524)
				)
				(justify left)
			)
		)
		(property "Value" ""
			(at 0 0 180)
			(layer "F.Fab")
			(effects
				(font
					(size 1.27 1.27)
				)
			)
		)
		(duplicate_pad_numbers_are_jumpers no)
		(fp_poly
			(pts
				(xy -0.2794 -0.1016) (xy 0.2794 -0.1016) (xy 0.2794 0.9906) (xy -0.2794 0.9906)
			)
			(stroke
				(width 0)
				(type default)
			)
			(fill no)
			(layer "F.CrtYd")
		)
		(fp_line
			(start 0.2794 0.9906)
			(end 0.2794 -0.1016)
			(stroke
				(width 0.1)
				(type default)
			)
			(layer "F.Fab")
		)
		(fp_line
			(start 0.2794 -0.1016)
			(end -0.2794 -0.1016)
			(stroke
				(width 0.1)
				(type default)
			)
			(layer "F.Fab")
		)
		(fp_line
			(start -0.2794 0.9906)
			(end 0.2794 0.9906)
			(stroke
				(width 0.1)
				(type default)
			)
			(layer "F.Fab")
		)
		(fp_line
			(start -0.2794 -0.1016)
			(end -0.2794 0.9906)
			(stroke
				(width 0.1)
				(type default)
			)
			(layer "F.Fab")
		)
		(pad "1" smd rect
			(at 0 0 180)
			(size 0.508 0.508)
			(layers "F.Cu" "F.Mask" "F.Paste")
			(net "FM_CPU1_RC_ERROR_N")
		)
		(pad "2" smd rect
			(at 0 0.889 180)
			(size 0.508 0.508)
			(layers "F.Cu" "F.Mask" "F.Paste")
			(net "FM_CPU1_RC_ERROR_R1_N")
		)
		(zone
			(layer "F.Cu")
			(hatch none 0.5)
			(connect_pads
				(clearance 0)
			)
			(min_thickness 0.25)
			(keepout
				(tracks not_allowed)
				(vias allowed)
				(pads allowed)
				(copperpour not_allowed)
				(footprints allowed)
			)
			(placement
				(enabled no)
				(sheetname "")
			)
			(fill
				(thermal_gap 0.5)
				(thermal_bridge_width 0.5)
				(island_removal_mode 0)
			)
			(polygon
				(pts
					(xy 411.9118 -103.0986) (xy 411.4038 -103.0986) (xy 411.4038 -102.7176) (xy 411.9118 -102.7176)
				)
			)
		)
		(zone
			(layer "F.Cu")
			(hatch none 0.5)
			(connect_pads
				(clearance 0)
			)
			(min_thickness 0.25)
			(keepout
				(tracks allowed)
				(vias not_allowed)
				(pads allowed)
				(copperpour not_allowed)
				(footprints allowed)
			)
			(placement
				(enabled no)
				(sheetname "")
			)
			(fill
				(thermal_gap 0.5)
				(thermal_bridge_width 0.5)
				(island_removal_mode 0)
			)
			(polygon
				(pts
					(xy 411.9118 -102.7176) (xy 411.4038 -102.7176) (xy 411.4038 -103.0986) (xy 411.9118 -103.0986)
				)
			)
		)
	)
	(footprint ""
		(layer "F.Cu")
		(at 11.89863 -3.541268 180)
		(property "Reference" "R12W32"
			(at -0.8382 -0.67818 180)
			(unlocked yes)
			(layer "F.SilkS")
			(effects
				(font
					(size 0.4064 0.254)
					(thickness 0.1524)
				)
				(justify left)
			)
		)
		(property "Value" ""
			(at 0 0 180)
			(layer "F.Fab")
			(effects
				(font
					(size 1.27 1.27)
				)
			)
		)
		(duplicate_pad_numbers_are_jumpers no)
		(fp_poly
			(pts
				(xy -0.2794 -0.1016) (xy 0.2794 -0.1016) (xy 0.2794 0.9906) (xy -0.2794 0.9906)
			)
			(stroke
				(width 0)
				(type default)
			)
			(fill no)
			(layer "F.CrtYd")
		)
		(fp_line
			(start 0.2794 0.9906)
			(end 0.2794 -0.1016)
			(stroke
				(width 0.1)
				(type default)
			)
			(layer "F.Fab")
		)
		(fp_line
			(start 0.2794 -0.1016)
			(end -0.2794 -0.1016)
			(stroke
				(width 0.1)
				(type default)
			)
			(layer "F.Fab")
		)
		(fp_line
			(start -0.2794 0.9906)
			(end 0.2794 0.9906)
			(stroke
				(width 0.1)
				(type default)
			)
			(layer "F.Fab")
		)
		(fp_line
			(start -0.2794 -0.1016)
			(end -0.2794 0.9906)
			(stroke
				(width 0.1)
				(type default)
			)
			(layer "F.Fab")
		)
		(pad "1" smd rect
			(at 0 0 180)
			(size 0.508 0.508)
			(layers "F.Cu" "F.Mask" "F.Paste")
			(net "TP_PVDDQ_GHJ_MP1")
		)
		(pad "2" smd rect
			(at 0 0.889 180)
			(size 0.508 0.508)
			(layers "F.Cu" "F.Mask" "F.Paste")
			(net "PWRGD_PVDDQ_GHJ")
		)
		(zone
			(layer "F.Cu")
			(hatch none 0.5)
			(connect_pads
				(clearance 0)
			)
			(min_thickness 0.25)
			(keepout
				(tracks not_allowed)
				(vias allowed)
				(pads allowed)
				(copperpour not_allowed)
				(footprints allowed)
			)
			(placement
				(enabled no)
				(sheetname "")
			)
			(fill
				(thermal_gap 0.5)
				(thermal_bridge_width 0.5)
				(island_removal_mode 0)
			)
			(polygon
				(pts
					(xy 12.15263 -4.176268) (xy 11.64463 -4.176268) (xy 11.64463 -3.795268) (xy 12.15263 -3.795268)
				)
			)
		)
		(zone
			(layer "F.Cu")
			(hatch none 0.5)
			(connect_pads
				(clearance 0)
			)
			(min_thickness 0.25)
			(keepout
				(tracks allowed)
				(vias not_allowed)
				(pads allowed)
				(copperpour not_allowed)
				(footprints allowed)
			)
			(placement
				(enabled no)
				(sheetname "")
			)
			(fill
				(thermal_gap 0.5)
				(thermal_bridge_width 0.5)
				(island_removal_mode 0)
			)
			(polygon
				(pts
					(xy 12.15263 -3.795268) (xy 11.64463 -3.795268) (xy 11.64463 -4.176268) (xy 12.15263 -4.176268)
				)
			)
		)
	)
)
